(kicad_pcb
	(version 20240108)
	(generator "pcbnew")
	(generator_version "8.0")
	(general
		(thickness 1.62)
		(legacy_teardrops no)
	)
	(paper "A4")
	(title_block
		(title "Jetson Orin Baseboard")
		(date "2025-03-12")
		(rev "1.3.4")
		(company "Antmicro Ltd")
		(comment 1 "www.antmicro.com")
		(comment 9 "footprints 667-671 of 677")
	)
	(layers
		(0 "F.Cu" signal)
		(1 "In1.Cu" signal)
		(2 "In2.Cu" signal)
		(3 "In3.Cu" signal)
		(4 "In4.Cu" jumper)
		(5 "In5.Cu" signal)
		(6 "In6.Cu" signal)
		(31 "B.Cu" signal)
		(32 "B.Adhes" user "B.Adhesive")
		(33 "F.Adhes" user "F.Adhesive")
		(34 "B.Paste" user)
		(35 "F.Paste" user)
		(36 "B.SilkS" user "B.Silkscreen")
		(37 "F.SilkS" user "F.Silkscreen")
		(38 "B.Mask" user)
		(39 "F.Mask" user)
		(40 "Dwgs.User" user "User.Drawings")
		(41 "Cmts.User" user "User.Comments")
		(42 "Eco1.User" user "User.Eco1")
		(43 "Eco2.User" user "User.Eco2")
		(44 "Edge.Cuts" user)
		(45 "Margin" user)
		(46 "B.CrtYd" user "B.Courtyard")
		(47 "F.CrtYd" user "F.Courtyard")
		(48 "B.Fab" user)
		(49 "F.Fab" user)
	)
	(footprint "antmicro-footprints:C_0402_1005Metric"
		(layer "B.Cu")
		(at 138 107.75 90)
		(descr "Capacitor SMD 0402")
		(tags "capacitor SMD 0402")
		(property "Reference" "C95"
			(at 1.1 1.3 -90)
			(layer "B.SilkS")
			(effects
				(font
					(size 0.7 0.7)
					(thickness 0.15)
				)
				(justify left bottom mirror)
			)
		)
		(property "Value" "C_1u_0402"
			(at 0 -1.4 -90)
			(layer "B.Fab")
			(effects
				(font
					(size 0.7 0.7)
					(thickness 0.15)
				)
				(justify left bottom mirror)
			)
		)
		(property "Footprint" "antmicro-footprints:C_0402_1005Metric"
			(at 0 0 90)
			(layer "F.Fab")
			(hide yes)
			(effects
				(font
					(size 1.27 1.27)
					(thickness 0.15)
				)
			)
		)
		(property "Datasheet" "https://product.tdk.com/en/search/capacitor/ceramic/mlcc/info?part_no=C1005X6S1A105K050BC"
			(at 0 0 90)
			(layer "F.Fab")
			(hide yes)
			(effects
				(font
					(size 1.27 1.27)
					(thickness 0.15)
				)
			)
		)
		(property "Author" "Antmicro"
			(at 245.75 -30.25 0)
			(layer "B.Fab")
			(hide yes)
			(effects
				(font
					(size 1 1)
					(thickness 0.15)
				)
				(justify mirror)
			)
		)
		(property "Dielectric" ""
			(at 245.75 -30.25 0)
			(layer "B.Fab")
			(hide yes)
			(effects
				(font
					(size 1 1)
					(thickness 0.15)
				)
				(justify mirror)
			)
		)
		(property "License" "Apache-2.0"
			(at 245.75 -30.25 0)
			(layer "B.Fab")
			(hide yes)
			(effects
				(font
					(size 1 1)
					(thickness 0.15)
				)
				(justify mirror)
			)
		)
		(property "MPN" "C1005X6S1A105K050BC"
			(at 245.75 -30.25 0)
			(layer "B.Fab")
			(hide yes)
			(effects
				(font
					(size 1 1)
					(thickness 0.15)
				)
				(justify mirror)
			)
		)
		(property "Manufacturer" "TDK"
			(at 245.75 -30.25 0)
			(layer "B.Fab")
			(hide yes)
			(effects
				(font
					(size 1 1)
					(thickness 0.15)
				)
				(justify mirror)
			)
		)
		(property "Val" "1u"
			(at 245.75 -30.25 0)
			(layer "B.Fab")
			(hide yes)
			(effects
				(font
					(size 1 1)
					(thickness 0.15)
				)
				(justify mirror)
			)
		)
		(property "Voltage" ""
			(at 245.75 -30.25 0)
			(layer "B.Fab")
			(hide yes)
			(effects
				(font
					(size 1 1)
					(thickness 0.15)
				)
				(justify mirror)
			)
		)
		(sheetname "CSI")
		(sheetfile "csi.kicad_sch")
		(attr smd)
		(fp_rect
			(start -0.925 0.47)
			(end 0.925 -0.47)
			(stroke
				(width 0.05)
				(type default)
			)
			(fill none)
			(layer "B.CrtYd")
		)
		(fp_line
			(start 0.504 -0.248)
			(end 0.504 0.25)
			(stroke
				(width 0.15)
				(type solid)
			)
			(layer "B.Fab")
		)
		(fp_line
			(start -0.494 -0.248)
			(end 0.504 -0.248)
			(stroke
				(width 0.15)
				(type solid)
			)
			(layer "B.Fab")
		)
		(fp_line
			(start 0.504 0.25)
			(end -0.494 0.25)
			(stroke
				(width 0.15)
				(type solid)
			)
			(layer "B.Fab")
		)
		(fp_line
			(start -0.494 0.25)
			(end -0.494 -0.248)
			(stroke
				(width 0.15)
				(type solid)
			)
			(layer "B.Fab")
		)
		(fp_text user "License: Apache-2.0"
			(at -0.932 -5.17 -90)
			(layer "B.Fab")
			(hide yes)
			(effects
				(font
					(size 0.7 0.7)
					(thickness 0.15)
				)
				(justify left bottom mirror)
			)
		)
		(fp_text user "${REFERENCE}"
			(at -0.932 -3.168 -90)
			(layer "B.Fab")
			(hide yes)
			(effects
				(font
					(size 0.7 0.7)
					(thickness 0.15)
				)
				(justify left bottom mirror)
			)
		)
		(fp_text user "Author: Antmicro"
			(at -0.932 -4.17 -90)
			(layer "B.Fab")
			(hide yes)
			(effects
				(font
					(size 0.7 0.7)
					(thickness 0.15)
				)
				(justify left bottom mirror)
			)
		)
		(pad "1" smd roundrect
			(at -0.48 0 90)
			(size 0.59 0.64)
			(layers "B.Cu" "B.Paste" "B.Mask")
			(roundrect_rratio 0.25)
			(net 1 "GND")
			(pintype "passive")
		)
		(pad "2" smd roundrect
			(at 0.48 0 90)
			(size 0.59 0.64)
			(layers "B.Cu" "B.Paste" "B.Mask")
			(roundrect_rratio 0.25)
			(net 109 "/CSI/CSIA_5V")
			(pintype "passive")
		)
	)
	(footprint "antmicro-footprints:TP_SMD_0.75mm"
		(layer "B.Cu")
		(at 101.14999 103.5508 180)
		(property "Reference" "TP40"
			(at 0 0.6 0)
			(layer "B.SilkS")
			(hide yes)
			(effects
				(font
					(size 0.7 0.7)
					(thickness 0.15)
				)
				(justify left bottom mirror)
			)
		)
		(property "Value" "TP_0.75mm_SMD"
			(at 0 -1.2 0)
			(layer "B.Fab")
			(effects
				(font
					(size 0.7 0.7)
					(thickness 0.15)
				)
				(justify left bottom mirror)
			)
		)
		(property "Footprint" "antmicro-footprints:TP_SMD_0.75mm"
			(at 0 0 180)
			(layer "F.Fab")
			(hide yes)
			(effects
				(font
					(size 1.27 1.27)
					(thickness 0.15)
				)
			)
		)
		(property "Author" "Antmicro"
			(at 202.29998 207.1016 0)
			(layer "B.Fab")
			(hide yes)
			(effects
				(font
					(size 1 1)
					(thickness 0.15)
				)
				(justify mirror)
			)
		)
		(property "License" "Apache-2.0"
			(at 202.29998 207.1016 0)
			(layer "B.Fab")
			(hide yes)
			(effects
				(font
					(size 1 1)
					(thickness 0.15)
				)
				(justify mirror)
			)
		)
		(property "MPN" ""
			(at 202.29998 207.1016 0)
			(layer "B.Fab")
			(hide yes)
			(effects
				(font
					(size 1 1)
					(thickness 0.15)
				)
				(justify mirror)
			)
		)
		(property "Manufacturer" ""
			(at 202.29998 207.1016 0)
			(layer "B.Fab")
			(hide yes)
			(effects
				(font
					(size 1 1)
					(thickness 0.15)
				)
				(justify mirror)
			)
		)
		(sheetname "CSI")
		(sheetfile "csi.kicad_sch")
		(attr exclude_from_pos_files exclude_from_bom)
		(fp_circle
			(center 0 0)
			(end 0.475 0)
			(stroke
				(width 0.05)
				(type default)
			)
			(fill none)
			(layer "B.CrtYd")
		)
		(fp_text user "License: Apache-2.0"
			(at -0.4 -5.101 0)
			(layer "B.Fab")
			(hide yes)
			(effects
				(font
					(size 0.7 0.7)
					(thickness 0.15)
				)
				(justify left bottom mirror)
			)
		)
		(fp_text user "Author: Antmicro"
			(at -0.4 -3.901 0)
			(layer "B.Fab")
			(hide yes)
			(effects
				(font
					(size 0.7 0.7)
					(thickness 0.15)
				)
				(justify left bottom mirror)
			)
		)
		(fp_text user "${REFERENCE}"
			(at -0.4 -2.7 0)
			(layer "B.Fab")
			(hide yes)
			(effects
				(font
					(size 0.7 0.7)
					(thickness 0.15)
				)
				(justify left bottom mirror)
			)
		)
		(pad "1" smd circle
			(at 0 0 180)
			(size 0.75 0.75)
			(layers "B.Cu" "B.Mask")
			(net 539 "/CSI/MUX_I2C_6_SDA")
			(pinfunction "1")
			(pintype "passive")
		)
	)
	(footprint "antmicro-footprints:R_0402_1005Metric"
		(layer "B.Cu")
		(at 57.55 109.45 180)
		(descr "Resistor SMD 0402")
		(tags "resistor SMD 0402")
		(property "Reference" "R56"
			(at -2.97 -0.41 0)
			(layer "B.SilkS")
			(effects
				(font
					(size 0.7 0.7)
					(thickness 0.15)
				)
				(justify left bottom mirror)
			)
		)
		(property "Value" "R_0R_0402"
			(at 0 -1.4 0)
			(layer "B.Fab")
			(effects
				(font
					(size 0.7 0.7)
					(thickness 0.15)
				)
				(justify left bottom mirror)
			)
		)
		(property "Footprint" "antmicro-footprints:R_0402_1005Metric"
			(at 0 0 180)
			(layer "F.Fab")
			(hide yes)
			(effects
				(font
					(size 1.27 1.27)
					(thickness 0.15)
				)
			)
		)
		(property "Datasheet" "https://industrial.panasonic.com/cdbs/www-data/pdf/RDA0000/AOA0000C301.pdf"
			(at 0 0 180)
			(layer "F.Fab")
			(hide yes)
			(effects
				(font
					(size 1.27 1.27)
					(thickness 0.15)
				)
			)
		)
		(property "Author" "Antmicro"
			(at 115.1 218.9 0)
			(layer "B.Fab")
			(hide yes)
			(effects
				(font
					(size 1 1)
					(thickness 0.15)
				)
				(justify mirror)
			)
		)
		(property "Current" "1A"
			(at 115.1 218.9 0)
			(layer "B.Fab")
			(hide yes)
			(effects
				(font
					(size 1 1)
					(thickness 0.15)
				)
				(justify mirror)
			)
		)
		(property "License" "Apache-2.0"
			(at 115.1 218.9 0)
			(layer "B.Fab")
			(hide yes)
			(effects
				(font
					(size 1 1)
					(thickness 0.15)
				)
				(justify mirror)
			)
		)
		(property "MPN" "ERJ2GE0R00X"
			(at 115.1 218.9 0)
			(layer "B.Fab")
			(hide yes)
			(effects
				(font
					(size 1 1)
					(thickness 0.15)
				)
				(justify mirror)
			)
		)
		(property "Manufacturer" "Panasonic"
			(at 115.1 218.9 0)
			(layer "B.Fab")
			(hide yes)
			(effects
				(font
					(size 1 1)
					(thickness 0.15)
				)
				(justify mirror)
			)
		)
		(property "Tolerance" ""
			(at 115.1 218.9 0)
			(layer "B.Fab")
			(hide yes)
			(effects
				(font
					(size 1 1)
					(thickness 0.15)
				)
				(justify mirror)
			)
		)
		(property "Val" "0R"
			(at 115.1 218.9 0)
			(layer "B.Fab")
			(hide yes)
			(effects
				(font
					(size 1 1)
					(thickness 0.15)
				)
				(justify mirror)
			)
		)
		(sheetname "USB Debug, DP")
		(sheetfile "usb.kicad_sch")
		(attr smd)
		(fp_rect
			(start -0.925 0.47)
			(end 0.925 -0.47)
			(stroke
				(width 0.05)
				(type default)
			)
			(fill none)
			(layer "B.CrtYd")
		)
		(fp_rect
			(start -0.5 0.25)
			(end 0.5 -0.25)
			(stroke
				(width 0.15)
				(type solid)
			)
			(fill none)
			(layer "B.Fab")
		)
		(fp_text user "Author: Antmicro"
			(at -0.95 -4.169 0)
			(layer "B.Fab")
			(hide yes)
			(effects
				(font
					(size 0.7 0.7)
					(thickness 0.15)
				)
				(justify left bottom mirror)
			)
		)
		(fp_text user "${REFERENCE}"
			(at -0.95 -3.168 0)
			(layer "B.Fab")
			(hide yes)
			(effects
				(font
					(size 0.7 0.7)
					(thickness 0.15)
				)
				(justify left bottom mirror)
			)
		)
		(fp_text user "License: Apache-2.0"
			(at -0.95 -5.169 0)
			(layer "B.Fab")
			(hide yes)
			(effects
				(font
					(size 0.7 0.7)
					(thickness 0.15)
				)
				(justify left bottom mirror)
			)
		)
		(pad "1" smd roundrect
			(at -0.48 0 180)
			(size 0.59 0.64)
			(layers "B.Cu" "B.Paste" "B.Mask")
			(roundrect_rratio 0.25)
			(net 477 "DEBUG_RXD")
			(pintype "passive")
		)
		(pad "2" smd roundrect
			(at 0.48 0 180)
			(size 0.59 0.64)
			(layers "B.Cu" "B.Paste" "B.Mask")
			(roundrect_rratio 0.25)
			(net 646 "Net-(U5-TXD)")
			(pintype "passive")
		)
	)
	(footprint "antmicro-footprints:C_0402_1005Metric"
		(layer "B.Cu")
		(at 138.91 100.11 180)
		(descr "Capacitor SMD 0402")
		(tags "capacitor SMD 0402")
		(property "Reference" "C96"
			(at -1.04 -1.29 0)
			(layer "B.SilkS")
			(effects
				(font
					(size 0.7 0.7)
					(thickness 0.15)
				)
				(justify left bottom mirror)
			)
		)
		(property "Value" "C_100n_0402"
			(at 0 -1.4 0)
			(layer "B.Fab")
			(effects
				(font
					(size 0.7 0.7)
					(thickness 0.15)
				)
				(justify left bottom mirror)
			)
		)
		(property "Footprint" "antmicro-footprints:C_0402_1005Metric"
			(at 0 0 180)
			(layer "F.Fab")
			(hide yes)
			(effects
				(font
					(size 1.27 1.27)
					(thickness 0.15)
				)
			)
		)
		(property "Datasheet" "https://www.murata.com/products/productdetail?partno=GRM155R61H104KE14%23"
			(at 0 0 180)
			(layer "F.Fab")
			(hide yes)
			(effects
				(font
					(size 1.27 1.27)
					(thickness 0.15)
				)
			)
		)
		(property "Author" "Antmicro"
			(at 277.82 200.22 0)
			(layer "B.Fab")
			(hide yes)
			(effects
				(font
					(size 1 1)
					(thickness 0.15)
				)
				(justify mirror)
			)
		)
		(property "Dielectric" "X5R"
			(at 277.82 200.22 0)
			(layer "B.Fab")
			(hide yes)
			(effects
				(font
					(size 1 1)
					(thickness 0.15)
				)
				(justify mirror)
			)
		)
		(property "License" "Apache-2.0"
			(at 277.82 200.22 0)
			(layer "B.Fab")
			(hide yes)
			(effects
				(font
					(size 1 1)
					(thickness 0.15)
				)
				(justify mirror)
			)
		)
		(property "MPN" "GRM155R61H104KE14D"
			(at 277.82 200.22 0)
			(layer "B.Fab")
			(hide yes)
			(effects
				(font
					(size 1 1)
					(thickness 0.15)
				)
				(justify mirror)
			)
		)
		(property "Manufacturer" "Murata"
			(at 277.82 200.22 0)
			(layer "B.Fab")
			(hide yes)
			(effects
				(font
					(size 1 1)
					(thickness 0.15)
				)
				(justify mirror)
			)
		)
		(property "Val" "100n"
			(at 277.82 200.22 0)
			(layer "B.Fab")
			(hide yes)
			(effects
				(font
					(size 1 1)
					(thickness 0.15)
				)
				(justify mirror)
			)
		)
		(property "Voltage" "50V"
			(at 277.82 200.22 0)
			(layer "B.Fab")
			(hide yes)
			(effects
				(font
					(size 1 1)
					(thickness 0.15)
				)
				(justify mirror)
			)
		)
		(sheetname "CSI")
		(sheetfile "csi.kicad_sch")
		(attr smd)
		(fp_rect
			(start -0.925 0.47)
			(end 0.925 -0.47)
			(stroke
				(width 0.05)
				(type default)
			)
			(fill none)
			(layer "B.CrtYd")
		)
		(fp_line
			(start 0.504 0.25)
			(end -0.494 0.25)
			(stroke
				(width 0.15)
				(type solid)
			)
			(layer "B.Fab")
		)
		(fp_line
			(start 0.504 -0.248)
			(end 0.504 0.25)
			(stroke
				(width 0.15)
				(type solid)
			)
			(layer "B.Fab")
		)
		(fp_line
			(start -0.494 0.25)
			(end -0.494 -0.248)
			(stroke
				(width 0.15)
				(type solid)
			)
			(layer "B.Fab")
		)
		(fp_line
			(start -0.494 -0.248)
			(end 0.504 -0.248)
			(stroke
				(width 0.15)
				(type solid)
			)
			(layer "B.Fab")
		)
		(fp_text user "Author: Antmicro"
			(at -0.932 -4.17 0)
			(layer "B.Fab")
			(hide yes)
			(effects
				(font
					(size 0.7 0.7)
					(thickness 0.15)
				)
				(justify left bottom mirror)
			)
		)
		(fp_text user "${REFERENCE}"
			(at -0.932 -3.168 0)
			(layer "B.Fab")
			(hide yes)
			(effects
				(font
					(size 0.7 0.7)
					(thickness 0.15)
				)
				(justify left bottom mirror)
			)
		)
		(fp_text user "License: Apache-2.0"
			(at -0.932 -5.17 0)
			(layer "B.Fab")
			(hide yes)
			(effects
				(font
					(size 0.7 0.7)
					(thickness 0.15)
				)
				(justify left bottom mirror)
			)
		)
		(pad "1" smd roundrect
			(at -0.48 0 180)
			(size 0.59 0.64)
			(layers "B.Cu" "B.Paste" "B.Mask")
			(roundrect_rratio 0.25)
			(net 1 "GND")
			(pintype "passive")
		)
		(pad "2" smd roundrect
			(at 0.48 0 180)
			(size 0.59 0.64)
			(layers "B.Cu" "B.Paste" "B.Mask")
			(roundrect_rratio 0.25)
			(net 112 "+1V8")
			(pintype "passive")
		)
	)
	(footprint "antmicro-footprints:C_0402_1005Metric"
		(layer "B.Cu")
		(at 67.2 108.2 -90)
		(descr "Capacitor SMD 0402")
		(tags "capacitor SMD 0402")
		(property "Reference" "C26"
			(at -0.96 0.44 90)
			(layer "B.SilkS")
			(effects
				(font
					(size 0.7 0.7)
					(thickness 0.15)
				)
				(justify left bottom mirror)
			)
		)
		(property "Value" "C_100n_0402"
			(at 0 -1.4 90)
			(layer "B.Fab")
			(effects
				(font
					(size 0.7 0.7)
					(thickness 0.15)
				)
				(justify left bottom mirror)
			)
		)
		(property "Footprint" "antmicro-footprints:C_0402_1005Metric"
			(at 0 0 -90)
			(layer "F.Fab")
			(hide yes)
			(effects
				(font
					(size 1.27 1.27)
					(thickness 0.15)
				)
			)
		)
		(property "Datasheet" "https://www.murata.com/products/productdetail?partno=GRM155R61H104KE14%23"
			(at 0 0 -90)
			(layer "F.Fab")
			(hide yes)
			(effects
				(font
					(size 1.27 1.27)
					(thickness 0.15)
				)
			)
		)
		(property "Author" "Antmicro"
			(at -41 175.4 0)
			(layer "B.Fab")
			(hide yes)
			(effects
				(font
					(size 1 1)
					(thickness 0.15)
				)
				(justify mirror)
			)
		)
		(property "Dielectric" "X5R"
			(at -41 175.4 0)
			(layer "B.Fab")
			(hide yes)
			(effects
				(font
					(size 1 1)
					(thickness 0.15)
				)
				(justify mirror)
			)
		)
		(property "License" "Apache-2.0"
			(at -41 175.4 0)
			(layer "B.Fab")
			(hide yes)
			(effects
				(font
					(size 1 1)
					(thickness 0.15)
				)
				(justify mirror)
			)
		)
		(property "MPN" "GRM155R61H104KE14D"
			(at -41 175.4 0)
			(layer "B.Fab")
			(hide yes)
			(effects
				(font
					(size 1 1)
					(thickness 0.15)
				)
				(justify mirror)
			)
		)
		(property "Manufacturer" "Murata"
			(at -41 175.4 0)
			(layer "B.Fab")
			(hide yes)
			(effects
				(font
					(size 1 1)
					(thickness 0.15)
				)
				(justify mirror)
			)
		)
		(property "Val" "100n"
			(at -41 175.4 0)
			(layer "B.Fab")
			(hide yes)
			(effects
				(font
					(size 1 1)
					(thickness 0.15)
				)
				(justify mirror)
			)
		)
		(property "Voltage" "50V"
			(at -41 175.4 0)
			(layer "B.Fab")
			(hide yes)
			(effects
				(font
					(size 1 1)
					(thickness 0.15)
				)
				(justify mirror)
			)
		)
		(sheetname "USB Debug, DP")
		(sheetfile "usb.kicad_sch")
		(attr smd)
		(fp_rect
			(start -0.925 0.47)
			(end 0.925 -0.47)
			(stroke
				(width 0.05)
				(type default)
			)
			(fill none)
			(layer "B.CrtYd")
		)
		(fp_line
			(start -0.494 0.25)
			(end -0.494 -0.248)
			(stroke
				(width 0.15)
				(type solid)
			)
			(layer "B.Fab")
		)
		(fp_line
			(start 0.504 0.25)
			(end -0.494 0.25)
			(stroke
				(width 0.15)
				(type solid)
			)
			(layer "B.Fab")
		)
		(fp_line
			(start -0.494 -0.248)
			(end 0.504 -0.248)
			(stroke
				(width 0.15)
				(type solid)
			)
			(layer "B.Fab")
		)
		(fp_line
			(start 0.504 -0.248)
			(end 0.504 0.25)
			(stroke
				(width 0.15)
				(type solid)
			)
			(layer "B.Fab")
		)
		(fp_text user "License: Apache-2.0"
			(at -0.932 -5.17 90)
			(layer "B.Fab")
			(hide yes)
			(effects
				(font
					(size 0.7 0.7)
					(thickness 0.15)
				)
				(justify left bottom mirror)
			)
		)
		(fp_text user "${REFERENCE}"
			(at -0.932 -3.168 90)
			(layer "B.Fab")
			(hide yes)
			(effects
				(font
					(size 0.7 0.7)
					(thickness 0.15)
				)
				(justify left bottom mirror)
			)
		)
		(fp_text user "Author: Antmicro"
			(at -0.932 -4.17 90)
			(layer "B.Fab")
			(hide yes)
			(effects
				(font
					(size 0.7 0.7)
					(thickness 0.15)
				)
				(justify left bottom mirror)
			)
		)
		(pad "1" smd roundrect
			(at -0.48 0 270)
			(size 0.59 0.64)
			(layers "B.Cu" "B.Paste" "B.Mask")
			(roundrect_rratio 0.25)
			(net 87 "+3V3")
			(pintype "passive")
		)
		(pad "2" smd roundrect
			(at 0.48 0 270)
			(size 0.59 0.64)
			(layers "B.Cu" "B.Paste" "B.Mask")
			(roundrect_rratio 0.25)
			(net 1 "GND")
			(pintype "passive")
		)
	)
)
